# SCM (Grand Teton) — schematic netlist excerpt (pin names and nets, part order shuffled) for the footprints in the layout excerpt that follows; sources: Cadence DE-HDL packaged netlist, KiCad conversion of 12092022_DA0F0TMDCD0_F0T_Management_Board_D_brd_V3_OCP.brd

R327  Q_RES  120 1% CHIP  pkg 0402LF  page 20 : A = GND ; B = M_BMC_DDR4_MA<1>
R496  Q_RES  4.7K 1% EMPTY  pkg 0402LF  page 45 : A = P3V3_AUX ; B = RST_SPI_PCH_FLASH_R1_N

(kicad_pcb
	(version 20260206)
	(generator "pcbnew")
	(generator_version "10.0")
	(general
		(thickness 1.6)
		(legacy_teardrops no)
	)
	(paper "A4")
	(title_block
		(title "12092022_DA0F0TMDCD0_F0T_Management_Board_D_brd_V3_OCP.brd")
		(comment 1 "Grand Teton / footprints 184-185 of 1440")
	)
	(layers
		(0 "F.Cu" signal "TOP")
		(4 "In1.Cu" signal "GND")
		(6 "In2.Cu" signal "IN1")
		(8 "In3.Cu" signal "GND1")
		(10 "In4.Cu" signal "IN2")
		(12 "In5.Cu" signal "VCC")
		(14 "In6.Cu" signal "VCC1")
		(16 "In7.Cu" signal "IN3")
		(18 "In8.Cu" signal "GND2")
		(20 "In9.Cu" signal "IN4")
		(22 "In10.Cu" signal "GND3")
		(2 "B.Cu" signal "BOTTOM")
		(9 "F.Adhes" user "F.Adhesive")
		(11 "B.Adhes" user "B.Adhesive")
		(13 "F.Paste" user "Package Geometry/Pastemask Top")
		(15 "B.Paste" user "Package Geometry/Pastemask Bottom")
		(5 "F.SilkS" user "Ref Des/Silkscreen Top")
		(7 "B.SilkS" user "Ref Des/Silkscreen Bottom")
		(1 "F.Mask" user "Board Geometry/Soldermask Top")
		(3 "B.Mask" user "Board Geometry/Soldermask Bottom")
		(17 "Dwgs.User" user "User.Drawings")
		(19 "Cmts.User" user "User.Comments")
		(21 "Eco1.User" user "User.Eco1")
		(23 "Eco2.User" user "User.Eco2")
		(25 "Edge.Cuts" user "Board Geometry/Outline")
		(27 "Margin" user)
		(31 "F.CrtYd" user "Package Geometry/Place Bound Top")
		(29 "B.CrtYd" user "Package Geometry/Place Bound Bottom")
		(35 "F.Fab" user "Ref Des/Assembly Top")
		(33 "B.Fab" user "Ref Des/Assembly Bottom")
	)
	(footprint ""
		(layer "F.Cu")
		(at 85.29955 -40.617394 180)
		(property "Reference" "R327"
			(at 0 0 180)
			(layer "F.SilkS")
			(hide yes)
			(effects
				(font
					(size 1.27 1.27)
				)
			)
		)
		(property "Value" ""
			(at 0 0 180)
			(layer "F.Fab")
			(effects
				(font
					(size 1.27 1.27)
				)
			)
		)
		(duplicate_pad_numbers_are_jumpers no)
		(fp_line
			(start 0.7874 0.4064)
			(end -0.7874 0.4064)
			(stroke
				(width 0.1524)
				(type default)
			)
			(layer "F.SilkS")
		)
		(fp_line
			(start 0.7874 -0.4064)
			(end 0.7874 0.4064)
			(stroke
				(width 0.1524)
				(type default)
			)
			(layer "F.SilkS")
		)
		(fp_line
			(start -0.7874 0.4064)
			(end -0.7874 -0.4064)
			(stroke
				(width 0.1524)
				(type default)
			)
			(layer "F.SilkS")
		)
		(fp_line
			(start -0.7874 -0.4064)
			(end 0.7874 -0.4064)
			(stroke
				(width 0.1524)
				(type default)
			)
			(layer "F.SilkS")
		)
		(fp_line
			(start 0.67945 0.3048)
			(end 0.120396 0.3048)
			(stroke
				(width 0.1)
				(type default)
			)
			(layer "F.Fab")
		)
		(fp_line
			(start 0.67945 -0.3048)
			(end 0.67945 0.3048)
			(stroke
				(width 0.1)
				(type default)
			)
			(layer "F.Fab")
		)
		(fp_line
			(start 0.12065 -0.2794)
			(end 0.12065 -0.3048)
			(stroke
				(width 0.1)
				(type default)
			)
			(layer "F.Fab")
		)
		(fp_line
			(start 0.12065 -0.3048)
			(end 0.67945 -0.3048)
			(stroke
				(width 0.1)
				(type default)
			)
			(layer "F.Fab")
		)
		(fp_line
			(start 0.120396 0.3048)
			(end 0.120396 0.2794)
			(stroke
				(width 0.1)
				(type default)
			)
			(layer "F.Fab")
		)
		(fp_line
			(start 0.120396 0.2794)
			(end -0.12065 0.2794)
			(stroke
				(width 0.1)
				(type default)
			)
			(layer "F.Fab")
		)
		(fp_line
			(start -0.12065 0.3048)
			(end -0.67945 0.3048)
			(stroke
				(width 0.1)
				(type default)
			)
			(layer "F.Fab")
		)
		(fp_line
			(start -0.12065 0.2794)
			(end -0.12065 0.3048)
			(stroke
				(width 0.1)
				(type default)
			)
			(layer "F.Fab")
		)
		(fp_line
			(start -0.12065 -0.2794)
			(end 0.12065 -0.2794)
			(stroke
				(width 0.1)
				(type default)
			)
			(layer "F.Fab")
		)
		(fp_line
			(start -0.12065 -0.305054)
			(end -0.12065 -0.2794)
			(stroke
				(width 0.1)
				(type default)
			)
			(layer "F.Fab")
		)
		(fp_line
			(start -0.67945 0.3048)
			(end -0.67945 -0.305054)
			(stroke
				(width 0.1)
				(type default)
			)
			(layer "F.Fab")
		)
		(fp_line
			(start -0.67945 -0.305054)
			(end -0.12065 -0.305054)
			(stroke
				(width 0.1)
				(type default)
			)
			(layer "F.Fab")
		)
		(pad "1" smd circle
			(at -0.40005 0 180)
			(size 0 0)
			(layers "F.Cu" "F.Mask" "F.Paste")
			(net "GND")
		)
		(pad "2" smd circle
			(at 0.40005 0 180)
			(size 0 0)
			(layers "F.Cu" "F.Mask" "F.Paste")
			(net "M_BMC_DDR4_MA<1>")
		)
	)
	(footprint ""
		(layer "F.Cu")
		(at 40.513 -89.027 180)
		(property "Reference" "R496"
			(at 0 0 180)
			(layer "F.SilkS")
			(hide yes)
			(effects
				(font
					(size 1.27 1.27)
				)
			)
		)
		(property "Value" ""
			(at 0 0 180)
			(layer "F.Fab")
			(effects
				(font
					(size 1.27 1.27)
				)
			)
		)
		(duplicate_pad_numbers_are_jumpers no)
		(fp_line
			(start 0.7874 0.4064)
			(end -0.7874 0.4064)
			(stroke
				(width 0.1524)
				(type default)
			)
			(layer "F.SilkS")
		)
		(fp_line
			(start 0.7874 -0.4064)
			(end 0.7874 0.4064)
			(stroke
				(width 0.1524)
				(type default)
			)
			(layer "F.SilkS")
		)
		(fp_line
			(start -0.7874 0.4064)
			(end -0.7874 -0.4064)
			(stroke
				(width 0.1524)
				(type default)
			)
			(layer "F.SilkS")
		)
		(fp_line
			(start -0.7874 -0.4064)
			(end 0.7874 -0.4064)
			(stroke
				(width 0.1524)
				(type default)
			)
			(layer "F.SilkS")
		)
		(fp_line
			(start 0.67945 0.3048)
			(end 0.120396 0.3048)
			(stroke
				(width 0.1)
				(type default)
			)
			(layer "F.Fab")
		)
		(fp_line
			(start 0.67945 -0.3048)
			(end 0.67945 0.3048)
			(stroke
				(width 0.1)
				(type default)
			)
			(layer "F.Fab")
		)
		(fp_line
			(start 0.12065 -0.2794)
			(end 0.12065 -0.3048)
			(stroke
				(width 0.1)
				(type default)
			)
			(layer "F.Fab")
		)
		(fp_line
			(start 0.12065 -0.3048)
			(end 0.67945 -0.3048)
			(stroke
				(width 0.1)
				(type default)
			)
			(layer "F.Fab")
		)
		(fp_line
			(start 0.120396 0.3048)
			(end 0.120396 0.2794)
			(stroke
				(width 0.1)
				(type default)
			)
			(layer "F.Fab")
		)
		(fp_line
			(start 0.120396 0.2794)
			(end -0.12065 0.2794)
			(stroke
				(width 0.1)
				(type default)
			)
			(layer "F.Fab")
		)
		(fp_line
			(start -0.12065 0.3048)
			(end -0.67945 0.3048)
			(stroke
				(width 0.1)
				(type default)
			)
			(layer "F.Fab")
		)
		(fp_line
			(start -0.12065 0.2794)
			(end -0.12065 0.3048)
			(stroke
				(width 0.1)
				(type default)
			)
			(layer "F.Fab")
		)
		(fp_line
			(start -0.12065 -0.2794)
			(end 0.12065 -0.2794)
			(stroke
				(width 0.1)
				(type default)
			)
			(layer "F.Fab")
		)
		(fp_line
			(start -0.12065 -0.305054)
			(end -0.12065 -0.2794)
			(stroke
				(width 0.1)
				(type default)
			)
			(layer "F.Fab")
		)
		(fp_line
			(start -0.67945 0.3048)
			(end -0.67945 -0.305054)
			(stroke
				(width 0.1)
				(type default)
			)
			(layer "F.Fab")
		)
		(fp_line
			(start -0.67945 -0.305054)
			(end -0.12065 -0.305054)
			(stroke
				(width 0.1)
				(type default)
			)
			(layer "F.Fab")
		)
		(pad "1" smd circle
			(at -0.40005 0 180)
			(size 0 0)
			(layers "F.Cu" "F.Mask" "F.Paste")
			(net "P3V3_AUX")
		)
		(pad "2" smd circle
			(at 0.40005 0 180)
			(size 0 0)
			(layers "F.Cu" "F.Mask" "F.Paste")
			(net "RST_SPI_PCH_FLASH_R1_N")
		)
	)
)
